# T6G (Grand Teton) — schematic netlist excerpt (pin names and nets, part order shuffled) for the footprints in the layout excerpt that follows; sources: Cadence DE-HDL packaged netlist, KiCad conversion of 04192023_DAF0TMB3IC0_F0TG_MB_C_brd_V02_OCP.brd

C3893  Q_CAP  22UF 4V 20% X6S  pkg C0402  page 68 : A = PVDD11_S3_P0 ; B = GND
R3869  Q_RES  0 5% EMPTY  pkg 0402LF  page 134 : A = P12V_OCP_SENSE_1 ; B = P12V_OCP_SFF_ISENSE_MAM_MAM

(kicad_pcb
	(version 20260206)
	(generator "pcbnew")
	(generator_version "10.0")
	(general
		(thickness 1.6)
		(legacy_teardrops no)
	)
	(paper "A4")
	(title_block
		(title "04192023_DAF0TMB3IC0_F0TG_MB_C_brd_V02_OCP.brd")
		(comment 1 "Grand Teton / footprints 1026-1027 of 8354")
	)
	(layers
		(0 "F.Cu" signal "TOP")
		(4 "In1.Cu" signal "GND")
		(6 "In2.Cu" signal "IN1")
		(8 "In3.Cu" signal "GND1")
		(10 "In4.Cu" signal "IN2")
		(12 "In5.Cu" signal "GND2")
		(14 "In6.Cu" signal "IN3")
		(16 "In7.Cu" signal "GND3")
		(18 "In8.Cu" signal "VCC")
		(20 "In9.Cu" signal "VCC1")
		(22 "In10.Cu" signal "GND4")
		(24 "In11.Cu" signal "IN4")
		(26 "In12.Cu" signal "GND5")
		(28 "In13.Cu" signal "IN5")
		(30 "In14.Cu" signal "GND6")
		(32 "In15.Cu" signal "IN6")
		(34 "In16.Cu" signal "GND7")
		(2 "B.Cu" signal "BOTTOM")
		(9 "F.Adhes" user "F.Adhesive")
		(11 "B.Adhes" user "B.Adhesive")
		(13 "F.Paste" user "Package Geometry/Pastemask Top")
		(15 "B.Paste" user "Package Geometry/Pastemask Bottom")
		(5 "F.SilkS" user "Ref Des/Silkscreen Top")
		(7 "B.SilkS" user "Ref Des/Silkscreen Bottom")
		(1 "F.Mask" user "Board Geometry/Soldermask Top")
		(3 "B.Mask" user "Board Geometry/Soldermask Bottom")
		(17 "Dwgs.User" user "User.Drawings")
		(19 "Cmts.User" user "User.Comments")
		(21 "Eco1.User" user "User.Eco1")
		(23 "Eco2.User" user "User.Eco2")
		(25 "Edge.Cuts" user "Board Geometry/Outline")
		(27 "Margin" user)
		(31 "F.CrtYd" user "Package Geometry/Place Bound Top")
		(29 "B.CrtYd" user "Package Geometry/Place Bound Bottom")
		(35 "F.Fab" user "Ref Des/Assembly Top")
		(33 "B.Fab" user "Ref Des/Assembly Bottom")
	)
	(footprint ""
		(layer "F.Cu")
		(at 363.645958 -259.845048)
		(property "Reference" "C3893"
			(at 0 0 0)
			(layer "F.SilkS")
			(hide yes)
			(effects
				(font
					(size 1.27 1.27)
				)
			)
		)
		(property "Value" ""
			(at 0 0 0)
			(layer "F.Fab")
			(effects
				(font
					(size 1.27 1.27)
				)
			)
		)
		(duplicate_pad_numbers_are_jumpers no)
		(fp_line
			(start -0.7874 -0.4064)
			(end 0.7874 -0.4064)
			(stroke
				(width 0.1524)
				(type default)
			)
			(layer "F.SilkS")
		)
		(fp_line
			(start -0.7874 0.4064)
			(end -0.7874 -0.4064)
			(stroke
				(width 0.1524)
				(type default)
			)
			(layer "F.SilkS")
		)
		(fp_line
			(start 0.7874 -0.4064)
			(end 0.7874 0.4064)
			(stroke
				(width 0.1524)
				(type default)
			)
			(layer "F.SilkS")
		)
		(fp_line
			(start 0.7874 0.4064)
			(end -0.7874 0.4064)
			(stroke
				(width 0.1524)
				(type default)
			)
			(layer "F.SilkS")
		)
		(fp_line
			(start -0.67945 -0.305054)
			(end -0.12065 -0.305054)
			(stroke
				(width 0.1)
				(type default)
			)
			(layer "F.Fab")
		)
		(fp_line
			(start -0.67945 0.3048)
			(end -0.67945 -0.305054)
			(stroke
				(width 0.1)
				(type default)
			)
			(layer "F.Fab")
		)
		(fp_line
			(start -0.12065 -0.305054)
			(end -0.12065 -0.2794)
			(stroke
				(width 0.1)
				(type default)
			)
			(layer "F.Fab")
		)
		(fp_line
			(start -0.12065 -0.2794)
			(end 0.12065 -0.2794)
			(stroke
				(width 0.1)
				(type default)
			)
			(layer "F.Fab")
		)
		(fp_line
			(start -0.12065 0.2794)
			(end -0.12065 0.3048)
			(stroke
				(width 0.1)
				(type default)
			)
			(layer "F.Fab")
		)
		(fp_line
			(start -0.12065 0.3048)
			(end -0.67945 0.3048)
			(stroke
				(width 0.1)
				(type default)
			)
			(layer "F.Fab")
		)
		(fp_line
			(start 0.120396 0.2794)
			(end -0.12065 0.2794)
			(stroke
				(width 0.1)
				(type default)
			)
			(layer "F.Fab")
		)
		(fp_line
			(start 0.120396 0.3048)
			(end 0.120396 0.2794)
			(stroke
				(width 0.1)
				(type default)
			)
			(layer "F.Fab")
		)
		(fp_line
			(start 0.12065 -0.3048)
			(end 0.67945 -0.3048)
			(stroke
				(width 0.1)
				(type default)
			)
			(layer "F.Fab")
		)
		(fp_line
			(start 0.12065 -0.2794)
			(end 0.12065 -0.3048)
			(stroke
				(width 0.1)
				(type default)
			)
			(layer "F.Fab")
		)
		(fp_line
			(start 0.67945 -0.3048)
			(end 0.67945 0.3048)
			(stroke
				(width 0.1)
				(type default)
			)
			(layer "F.Fab")
		)
		(fp_line
			(start 0.67945 0.3048)
			(end 0.120396 0.3048)
			(stroke
				(width 0.1)
				(type default)
			)
			(layer "F.Fab")
		)
		(pad "1" smd circle
			(at -0.40005 0)
			(size 0 0)
			(layers "F.Cu" "F.Mask" "F.Paste")
			(net "PVDD11_S3_P0")
		)
		(pad "2" smd circle
			(at 0.40005 0)
			(size 0 0)
			(layers "F.Cu" "F.Mask" "F.Paste")
			(net "GND")
		)
	)
	(footprint ""
		(layer "F.Cu")
		(at 435.208172 -32.173418 -90)
		(property "Reference" "R3869"
			(at 0 0 270)
			(layer "F.SilkS")
			(hide yes)
			(effects
				(font
					(size 1.27 1.27)
				)
			)
		)
		(property "Value" ""
			(at 0 0 270)
			(layer "F.Fab")
			(effects
				(font
					(size 1.27 1.27)
				)
			)
		)
		(duplicate_pad_numbers_are_jumpers no)
		(fp_line
			(start -0.7874 0.4064)
			(end -0.7874 -0.4064)
			(stroke
				(width 0.1524)
				(type default)
			)
			(layer "F.SilkS")
		)
		(fp_line
			(start 0.7874 0.4064)
			(end -0.7874 0.4064)
			(stroke
				(width 0.1524)
				(type default)
			)
			(layer "F.SilkS")
		)
		(fp_line
			(start -0.7874 -0.4064)
			(end 0.7874 -0.4064)
			(stroke
				(width 0.1524)
				(type default)
			)
			(layer "F.SilkS")
		)
		(fp_line
			(start 0.7874 -0.4064)
			(end 0.7874 0.4064)
			(stroke
				(width 0.1524)
				(type default)
			)
			(layer "F.SilkS")
		)
		(fp_line
			(start -0.67945 0.3048)
			(end -0.67945 -0.305054)
			(stroke
				(width 0.1)
				(type default)
			)
			(layer "F.Fab")
		)
		(fp_line
			(start -0.12065 0.3048)
			(end -0.67945 0.3048)
			(stroke
				(width 0.1)
				(type default)
			)
			(layer "F.Fab")
		)
		(fp_line
			(start 0.120396 0.3048)
			(end 0.120396 0.2794)
			(stroke
				(width 0.1)
				(type default)
			)
			(layer "F.Fab")
		)
		(fp_line
			(start 0.67945 0.3048)
			(end 0.120396 0.3048)
			(stroke
				(width 0.1)
				(type default)
			)
			(layer "F.Fab")
		)
		(fp_line
			(start -0.12065 0.2794)
			(end -0.12065 0.3048)
			(stroke
				(width 0.1)
				(type default)
			)
			(layer "F.Fab")
		)
		(fp_line
			(start 0.120396 0.2794)
			(end -0.12065 0.2794)
			(stroke
				(width 0.1)
				(type default)
			)
			(layer "F.Fab")
		)
		(fp_line
			(start -0.12065 -0.2794)
			(end 0.12065 -0.2794)
			(stroke
				(width 0.1)
				(type default)
			)
			(layer "F.Fab")
		)
		(fp_line
			(start 0.12065 -0.2794)
			(end 0.12065 -0.3048)
			(stroke
				(width 0.1)
				(type default)
			)
			(layer "F.Fab")
		)
		(fp_line
			(start 0.12065 -0.3048)
			(end 0.67945 -0.3048)
			(stroke
				(width 0.1)
				(type default)
			)
			(layer "F.Fab")
		)
		(fp_line
			(start 0.67945 -0.3048)
			(end 0.67945 0.3048)
			(stroke
				(width 0.1)
				(type default)
			)
			(layer "F.Fab")
		)
		(fp_line
			(start -0.67945 -0.305054)
			(end -0.12065 -0.305054)
			(stroke
				(width 0.1)
				(type default)
			)
			(layer "F.Fab")
		)
		(fp_line
			(start -0.12065 -0.305054)
			(end -0.12065 -0.2794)
			(stroke
				(width 0.1)
				(type default)
			)
			(layer "F.Fab")
		)
		(pad "1" smd circle
			(at -0.40005 0 270)
			(size 0 0)
			(layers "F.Cu" "F.Mask" "F.Paste")
			(net "P12V_OCP_SENSE_1")
		)
		(pad "2" smd circle
			(at 0.40005 0 270)
			(size 0 0)
			(layers "F.Cu" "F.Mask" "F.Paste")
			(net "P12V_OCP_SFF_ISENSE_MAM_MAM")
		)
	)
)
